# S9S_MB_2U (Grand Teton) — schematic netlist excerpt (pin names and nets, part order shuffled) for the footprints in the layout excerpt that follows; sources: Cadence DE-HDL packaged netlist, KiCad conversion of 03242023_DA0F0TMBIJ0_F0T_Motherboard_J_brd_V01_OCP.brd

J16  SCONN288_ADR50017P087CC  SCONN288_ADR50017-P087CC IO  pkg DDR288S_1-1VXB  page 97
  VIN_BULK0  = P12V_S3_AUX_CPU0_NVDIMM
  RFU0  = TP_CHH_CPU0_DIMM2_FRU_0
  VIN_MGMT  = P3V3_AUX
  HSCL  = I3C_SPD_DDREFGH_CPU0_LVC1_SCL_7
  HSDA  = I3C_SPD_DDREFGH_CPU0_LVC1_SDA
  VSS0  = GND
  DQ0_A  = M_H_CPU0_SA_DQ<0>
  VSS1  = GND
  DQ1_A  = M_H_CPU0_SA_DQ<1>
  VSS2  = GND
  DQS0_A_T  = M_H_CPU0_SA_DQS_DP<0>
  DQS0_A_C  = M_H_CPU0_SA_DQS_DN<0>
  VSS3  = GND
  DQ4_A  = M_H_CPU0_SA_DQ<4>
  VSS4  = GND
  DQ5_A  = M_H_CPU0_SA_DQ<5>
  VSS5  = GND
  DQ8_A  = M_H_CPU0_SA_DQ<8>
  VSS6  = GND
  DQ9_A  = M_H_CPU0_SA_DQ<9>
  VSS7  = GND
  DQS1_A_T  = M_H_CPU0_SA_DQS_DP<1>
  DQS1_A_C  = M_H_CPU0_SA_DQS_DN<1>
  VSS8  = GND
  DQ12_A  = M_H_CPU0_SA_DQ<12>
  VSS9  = GND
  DQ13_A  = M_H_CPU0_SA_DQ<13>
  VSS10  = GND
  DQ16_A  = M_H_CPU0_SA_DQ<16>
  VSS11  = GND
  DQ17_A  = M_H_CPU0_SA_DQ<17>
  VSS12  = GND
  DQS2_A_T  = M_H_CPU0_SA_DQS_DP<2>
  DQS2_A_C  = M_H_CPU0_SA_DQS_DN<2>
  VSS13  = GND
  DQ20_A  = M_H_CPU0_SA_DQ<20>
  VSS14  = GND
  DQ21_A  = M_H_CPU0_SA_DQ<21>
  VSS15  = GND
  DQ24_A  = M_H_CPU0_SA_DQ<24>
  VSS16  = GND
  DQ25_A  = M_H_CPU0_SA_DQ<25>
  VSS17  = GND
  DQS3_A_T  = M_H_CPU0_SA_DQS_DP<3>
  DQS3_A_C  = M_H_CPU0_SA_DQS_DN<3>
  VSS18  = GND
  DQ28_A  = M_H_CPU0_SA_DQ<28>
  VSS19  = GND
  DQ29_A  = M_H_CPU0_SA_DQ<29>
  VSS20  = GND
  CB0_A  = M_H_CPU0_SA_CB<0>
  VSS21  = GND
  CB1_A  = M_H_CPU0_SA_CB<1>
  VSS22  = GND
  DQS4_A_T  = M_H_CPU0_SA_DQS_DP<4>
  DQS4_A_C  = M_H_CPU0_SA_DQS_DN<4>
  VSS23  = GND
  CB4_A  = M_H_CPU0_SA_CB<4>
  VSS24  = GND
  CB5_A  = M_H_CPU0_SA_CB<5>
  VSS25  = GND
  ALERT_N  = M_H_CPU0_ALERT_N
  VSS26  = GND
  CS0_A_N  = M_H_CPU0_SA_CS_N<2>
  VSS27  = GND
  CA0_A  = M_H_CPU0_SA_CA<0>
  VSS28  = GND
  CA2_A  = M_H_CPU0_SA_CA<2>
  VSS29  = GND
  CA4_A  = M_H_CPU0_SA_CA<4>
  VSS30  = GND
  CA6_A  = M_H_CPU0_SA_CA<6>
  VSS31  = GND
  PAR_A  = M_H_CPU0_SA_PAR
  VSS32  = GND
  CA0_B  = M_H_CPU0_SB_CA<0>
  VSS33  = GND
  CA2_B  = M_H_CPU0_SB_CA<2>
  VSS34  = GND
  CA4_B  = M_H_CPU0_SB_CA<4>
  VSS35  = GND
  CA6_B  = M_H_CPU0_SB_CA<6>
  VSS36  = GND
  CS0_B_N  = M_H_CPU0_SB_CS_N<2>
  VSS37  = GND
  \lbd||rsp_a_n\  = M_H_CPU0_SA_RSP<1>
  \lbs||rsp_b_n\  = M_H_CPU0_SB_RSP<1>
  VSS38  = GND
  CB4_B  = M_H_CPU0_SB_CB<4>
  VSS39  = GND
  CB5_B  = M_H_CPU0_SB_CB<5>
  VSS40  = GND
  \dqs9_b_t||tdqs9_b_t||dbi4_b_n\  = M_H_CPU0_SB_DQS_DP<9>
  \dqs9_b_c||tdqs9_b_c\  = M_H_CPU0_SB_DQS_DN<9>
  VSS41  = GND
  CB0_B  = M_H_CPU0_SB_CB<0>
  VSS42  = GND
  CB1_B  = M_H_CPU0_SB_CB<1>
  VSS43  = GND
  DQ0_B  = M_H_CPU0_SB_DQ<0>
  VSS44  = GND
  DQ1_B  = M_H_CPU0_SB_DQ<1>
  VSS45  = GND
  DQS0_B_T  = M_H_CPU0_SB_DQS_DP<0>
  DQS0_B_C  = M_H_CPU0_SB_DQS_DN<0>
  VSS46  = GND
  DQ4_B  = M_H_CPU0_SB_DQ<4>
  VSS47  = GND
  DQ5_B  = M_H_CPU0_SB_DQ<5>
  VSS48  = GND
  DQ8_B  = M_H_CPU0_SB_DQ<8>
  VSS49  = GND
  DQ9_B  = M_H_CPU0_SB_DQ<9>
  VSS50  = GND
  DQS1_B_T  = M_H_CPU0_SB_DQS_DP<1>
  DQS1_B_C  = M_H_CPU0_SB_DQS_DN<1>
  VSS51  = GND
  DQ12_B  = M_H_CPU0_SB_DQ<12>
  VSS52  = GND
  DQ13_B  = M_H_CPU0_SB_DQ<13>
  VSS53  = GND
  DQ16_B  = M_H_CPU0_SB_DQ<16>
  VSS54  = GND
  DQ17_B  = M_H_CPU0_SB_DQ<17>
  VSS55  = GND
  DQS2_B_T  = M_H_CPU0_SB_DQS_DP<2>
  DQS2_B_C  = M_H_CPU0_SB_DQS_DN<2>
  VSS56  = GND
  DQ20_B  = M_H_CPU0_SB_DQ<20>
  VSS57  = GND
  DQ21_B  = M_H_CPU0_SB_DQ<21>
  VSS58  = GND
  DQ24_B  = M_H_CPU0_SB_DQ<24>
  VSS59  = GND
  DQ25_B  = M_H_CPU0_SB_DQ<25>
  VSS60  = GND
  DQS3_B_T  = M_H_CPU0_SB_DQS_DP<3>
  DQS3_B_C  = M_H_CPU0_SB_DQS_DN<3>
  VSS61  = GND
  DQ28_B  = M_H_CPU0_SB_DQ<28>
  VSS62  = GND
  DQ29_B  = M_H_CPU0_SB_DQ<29>
  VSS63  = GND
  RFU1  = TP_CHH_CPU0_DIMM2_FRU_1
  VIN_BULK1  = P12V_S3_AUX_CPU0_NVDIMM
  VIN_BULK2  = P12V_S3_AUX_CPU0_NVDIMM
  \pwr_good||fail_n\  = PWRGD_CHH_CPU0_DIMM2
  HSA  = PD_CHH_CPU0_DIMM2_SAA
  RFU2  = TP_CHH_CPU0_DIMM2_FRU_2
  RFU3  = TP_CHH_CPU0_DIMM2_FRU_3
  VSS64  = GND
  DQ2_A  = M_H_CPU0_SA_DQ<2>
  VSS65  = GND
  DQ3_A  = M_H_CPU0_SA_DQ<3>
  VSS66  = GND
  \dqs5_a_c||tdqs5_a_c||dqs5_a_t||tdqs5_a_t\  = M_H_CPU0_SA_DQS_DN<5>
  \dqs5_a_t||tdqs5_a_t\  = M_H_CPU0_SA_DQS_DP<5>
  VSS67  = GND
  DQ6_A  = M_H_CPU0_SA_DQ<6>
  VSS68  = GND
  DQ7_A  = M_H_CPU0_SA_DQ<7>
  VSS69  = GND
  DQ10_A  = M_H_CPU0_SA_DQ<10>
  VSS70  = GND
  DQ11_A  = M_H_CPU0_SA_DQ<11>
  VSS71  = GND
  \dqs6_a_c||tdqs6_a_c||dqs6_a_t||tdqs6_a_t\  = M_H_CPU0_SA_DQS_DN<6>
  \dqs6_a_t||tdqs6_a_t\  = M_H_CPU0_SA_DQS_DP<6>
  VSS72  = GND
  DQ14_A  = M_H_CPU0_SA_DQ<14>
  VSS73  = GND
  DQ15_A  = M_H_CPU0_SA_DQ<15>
  VSS74  = GND
  DQ18_A  = M_H_CPU0_SA_DQ<18>
  VSS75  = GND
  DQ19_A  = M_H_CPU0_SA_DQ<19>
  VSS76  = GND
  \dqs7_a_c||tdqs7_a_c\  = M_H_CPU0_SA_DQS_DN<7>
  \dqs7_a_t||tdqs7_a_t\  = M_H_CPU0_SA_DQS_DP<7>
  VSS77  = GND
  DQ22_A  = M_H_CPU0_SA_DQ<22>
  VSS78  = GND
  DQ23_A  = M_H_CPU0_SA_DQ<23>
  VSS79  = GND
  DQ26_A  = M_H_CPU0_SA_DQ<26>
  VSS80  = GND
  DQ27_A  = M_H_CPU0_SA_DQ<27>
  VSS81  = GND
  \dqs8_a_c||tdqs8_a_c\  = M_H_CPU0_SA_DQS_DN<8>
  \dqs8_a_t||tdqs8_a_t\  = M_H_CPU0_SA_DQS_DP<8>
  VSS82  = GND
  DQ30_A  = M_H_CPU0_SA_DQ<30>
  VSS83  = GND
  DQ31_A  = M_H_CPU0_SA_DQ<31>
  VSS84  = GND
  CB2_A  = M_H_CPU0_SA_CB<2>
  VSS85  = GND
  CB3_A  = M_H_CPU0_SA_CB<3>
  VSS86  = GND
  \dqs9_a_c||tdqs9_a_c\  = M_H_CPU0_SA_DQS_DN<9>
  \dqs9_a_t||tdqs9_a_t\  = M_H_CPU0_SA_DQS_DP<9>
  VSS87  = GND
  CB6_A  = M_H_CPU0_SA_CB<6>
  VSS88  = GND
  CB7_A  = M_H_CPU0_SA_CB<7>
  VSS89  = GND
  RESET_N  = RST_M_GH_CPU0_FPGA_N
  VSS90  = GND
  CS1_A_N  = M_H_CPU0_SA_CS_N<3>
  VSS91  = GND
  CA1_A  = M_H_CPU0_SA_CA<1>
  VSS92  = GND
  CA3_A  = M_H_CPU0_SA_CA<3>
  VSS93  = GND
  CA5_A  = M_H_CPU0_SA_CA<5>
  VSS94  = GND
  CK_T  = M_H_CPU0_CLK_DP<1>
  CK_C  = M_H_CPU0_CLK_DN<1>
  VSS95  = GND
  RFU4  = TP_CHH_CPU0_DIMM2_FRU_4
  CA1_B  = M_H_CPU0_SB_CA<1>
  VSS96  = GND
  CA3_B  = M_H_CPU0_SB_CA<3>
  VSS97  = GND
  CA5_B  = M_H_CPU0_SB_CA<5>
  VSS98  = GND
  PAR_B  = M_H_CPU0_SB_PAR
  VSS99  = GND
  CS1_B_N  = M_H_CPU0_SB_CS_N<3>
  VSS100  = GND
  RFU5  = TP_CHH_CPU0_DIMM2_FRU_5
  RFU6  = TP_CHH_CPU0_DIMM2_FRU_6
  VSS101  = GND
  CB6_B  = M_H_CPU0_SB_CB<6>
  VSS102  = GND
  CB7_B  = M_H_CPU0_SB_CB<7>
  VSS103  = GND
  DQS4_B_C  = M_H_CPU0_SB_DQS_DN<4>
  DQS4_B_T  = M_H_CPU0_SB_DQS_DP<4>
  VSS104  = GND
  CB2_B  = M_H_CPU0_SB_CB<2>
  VSS105  = GND
  CB3_B  = M_H_CPU0_SB_CB<3>
  VSS106  = GND
  DQ2_B  = M_H_CPU0_SB_DQ<2>
  VSS107  = GND
  DQ3_B  = M_H_CPU0_SB_DQ<3>
  VSS108  = GND
  \dqs5_b_c||tdqs5_b_c\  = M_H_CPU0_SB_DQS_DN<5>
  \dqs5_b_t||tdqs5_b_t\  = M_H_CPU0_SB_DQS_DP<5>
  VSS109  = GND
  DQ6_B  = M_H_CPU0_SB_DQ<6>
  VSS110  = GND
  DQ7_B  = M_H_CPU0_SB_DQ<7>
  VSS111  = GND
  DQ10_B  = M_H_CPU0_SB_DQ<10>
  VSS112  = GND
  DQ11_B  = M_H_CPU0_SB_DQ<11>
  VSS113  = GND
  \dqs6_b_c||tdqs6_b_c\  = M_H_CPU0_SB_DQS_DN<6>
  \dqs6_b_t||tdqs6_b_t\  = M_H_CPU0_SB_DQS_DP<6>
  VSS114  = GND
  DQ14_B  = M_H_CPU0_SB_DQ<14>
  VSS115  = GND
  DQ15_B  = M_H_CPU0_SB_DQ<15>
  VSS116  = GND
  DQ18_B  = M_H_CPU0_SB_DQ<18>
  VSS117  = GND
  DQ19_B  = M_H_CPU0_SB_DQ<19>
  VSS118  = GND
  \dqs7_b_c||tdqs7_b_c\  = M_H_CPU0_SB_DQS_DN<7>
  \dqs7_b_t||tdqs7_b_t\  = M_H_CPU0_SB_DQS_DP<7>
  VSS119  = GND
  DQ22_B  = M_H_CPU0_SB_DQ<22>
  VSS120  = GND
  DQ23_B  = M_H_CPU0_SB_DQ<23>
  VSS121  = GND
  DQ26_B  = M_H_CPU0_SB_DQ<26>
  VSS122  = GND
  DQ27_B  = M_H_CPU0_SB_DQ<27>
  VSS123  = GND
  \dqs8_b_c||tdqs8_b_c\  = M_H_CPU0_SB_DQS_DN<8>
  \dqs8_b_t||tdqs8_b_t\  = M_H_CPU0_SB_DQS_DP<8>
  VSS124  = GND
  DQ30_B  = M_H_CPU0_SB_DQ<30>
  VSS125  = GND
  DQ31_B  = M_H_CPU0_SB_DQ<31>
  VSS126  = GND
  G1  = GND
  G2  = GND
  G3  = GND

(kicad_pcb
	(version 20260206)
	(generator "pcbnew")
	(generator_version "10.0")
	(general
		(thickness 1.6)
		(legacy_teardrops no)
	)
	(paper "A4")
	(title_block
		(title "03242023_DA0F0TMBIJ0_F0T_Motherboard_J_brd_V01_OCP.brd")
		(comment 1 "Grand Teton / footprint 1690 of 6105 (J16), pads 229-274 of 291")
	)
	(layers
		(0 "F.Cu" signal "TOP")
		(4 "In1.Cu" signal "GND")
		(6 "In2.Cu" signal "IN1")
		(8 "In3.Cu" signal "GND1")
		(10 "In4.Cu" signal "IN2")
		(12 "In5.Cu" signal "GND2")
		(14 "In6.Cu" signal "IN3")
		(16 "In7.Cu" signal "GND3")
		(18 "In8.Cu" signal "VCC")
		(20 "In9.Cu" signal "VCC1")
		(22 "In10.Cu" signal "GND4")
		(24 "In11.Cu" signal "IN4")
		(26 "In12.Cu" signal "GND5")
		(28 "In13.Cu" signal "IN5")
		(30 "In14.Cu" signal "GND6")
		(32 "In15.Cu" signal "IN6")
		(34 "In16.Cu" signal "GND7")
		(2 "B.Cu" signal "BOTTOM")
		(9 "F.Adhes" user "F.Adhesive")
		(11 "B.Adhes" user "B.Adhesive")
		(13 "F.Paste" user "Package Geometry/Pastemask Top")
		(15 "B.Paste" user "Package Geometry/Pastemask Bottom")
		(5 "F.SilkS" user "Ref Des/Silkscreen Top")
		(7 "B.SilkS" user "Ref Des/Silkscreen Bottom")
		(1 "F.Mask" user "Board Geometry/Soldermask Top")
		(3 "B.Mask" user "Board Geometry/Soldermask Bottom")
		(17 "Dwgs.User" user "User.Drawings")
		(19 "Cmts.User" user "User.Comments")
		(21 "Eco1.User" user "User.Eco1")
		(23 "Eco2.User" user "User.Eco2")
		(25 "Edge.Cuts" user "Board Geometry/Outline")
		(27 "Margin" user)
		(31 "F.CrtYd" user "Package Geometry/Place Bound Top")
		(29 "B.CrtYd" user "Package Geometry/Place Bound Bottom")
		(35 "F.Fab" user "Ref Des/Assembly Top")
		(33 "B.Fab" user "Ref Des/Assembly Bottom")
	)
	(footprint ""
		(layer "F.Cu")
		(at 454.066148 -258.091686)
		(property "Reference" "J16"
			(at -0.279908 -81.779872 0)
			(unlocked yes)
			(layer "F.SilkS")
			(effects
				(font
					(size 0.7874 0.5842)
					(thickness 0.1524)
				)
				(justify left)
			)
		)
		(property "Value" ""
			(at 0 0 0)
			(layer "F.Fab")
			(effects
				(font
					(size 1.27 1.27)
				)
			)
		)
		(duplicate_pad_numbers_are_jumpers no)
		(pad "229" smd rect
			(at 2.050034 13.17498 270)
			(size 0.519938 1.4986)
			(layers "F.Cu" "F.Mask" "F.Paste")
			(net "M_H_CPU0_SB_CS_N<3>")
		)
		(pad "230" smd rect
			(at 2.050034 14.025118 270)
			(size 0.519938 1.4986)
			(layers "F.Cu" "F.Mask" "F.Paste")
			(net "GND")
		)
		(pad "231" smd rect
			(at 2.050034 14.875002 270)
			(size 0.519938 1.4986)
			(layers "F.Cu" "F.Mask" "F.Paste")
			(net "TP_CHH_CPU0_DIMM2_FRU_5")
		)
		(pad "232" smd rect
			(at 2.050034 15.724886 270)
			(size 0.519938 1.4986)
			(layers "F.Cu" "F.Mask" "F.Paste")
			(net "TP_CHH_CPU0_DIMM2_FRU_6")
		)
		(pad "233" smd rect
			(at 2.050034 16.575024 270)
			(size 0.519938 1.4986)
			(layers "F.Cu" "F.Mask" "F.Paste")
			(net "GND")
		)
		(pad "234" smd rect
			(at 2.050034 17.424908 270)
			(size 0.519938 1.4986)
			(layers "F.Cu" "F.Mask" "F.Paste")
			(net "M_H_CPU0_SB_CB<6>")
		)
		(pad "235" smd rect
			(at 2.050034 18.275046 270)
			(size 0.519938 1.4986)
			(layers "F.Cu" "F.Mask" "F.Paste")
			(net "GND")
		)
		(pad "236" smd rect
			(at 2.050034 19.12493 270)
			(size 0.519938 1.4986)
			(layers "F.Cu" "F.Mask" "F.Paste")
			(net "M_H_CPU0_SB_CB<7>")
		)
		(pad "237" smd rect
			(at 2.050034 19.975068 270)
			(size 0.519938 1.4986)
			(layers "F.Cu" "F.Mask" "F.Paste")
			(net "GND")
		)
		(pad "238" smd rect
			(at 2.050034 20.824952 270)
			(size 0.519938 1.4986)
			(layers "F.Cu" "F.Mask" "F.Paste")
			(net "M_H_CPU0_SB_DQS_DN<4>")
		)
		(pad "239" smd rect
			(at 2.050034 21.67509 270)
			(size 0.519938 1.4986)
			(layers "F.Cu" "F.Mask" "F.Paste")
			(net "M_H_CPU0_SB_DQS_DP<4>")
		)
		(pad "240" smd rect
			(at 2.050034 22.524974 270)
			(size 0.519938 1.4986)
			(layers "F.Cu" "F.Mask" "F.Paste")
			(net "GND")
		)
		(pad "241" smd rect
			(at 2.050034 23.375112 270)
			(size 0.519938 1.4986)
			(layers "F.Cu" "F.Mask" "F.Paste")
			(net "M_H_CPU0_SB_CB<2>")
		)
		(pad "242" smd rect
			(at 2.050034 24.224996 270)
			(size 0.519938 1.4986)
			(layers "F.Cu" "F.Mask" "F.Paste")
			(net "GND")
		)
		(pad "243" smd rect
			(at 2.050034 25.07488 270)
			(size 0.519938 1.4986)
			(layers "F.Cu" "F.Mask" "F.Paste")
			(net "M_H_CPU0_SB_CB<3>")
		)
		(pad "244" smd rect
			(at 2.050034 25.925018 270)
			(size 0.519938 1.4986)
			(layers "F.Cu" "F.Mask" "F.Paste")
			(net "GND")
		)
		(pad "245" smd rect
			(at 2.050034 26.774902 270)
			(size 0.519938 1.4986)
			(layers "F.Cu" "F.Mask" "F.Paste")
			(net "M_H_CPU0_SB_DQ<2>")
		)
		(pad "246" smd rect
			(at 2.050034 27.62504 270)
			(size 0.519938 1.4986)
			(layers "F.Cu" "F.Mask" "F.Paste")
			(net "GND")
		)
		(pad "247" smd rect
			(at 2.050034 28.474924 270)
			(size 0.519938 1.4986)
			(layers "F.Cu" "F.Mask" "F.Paste")
			(net "M_H_CPU0_SB_DQ<3>")
		)
		(pad "248" smd rect
			(at 2.050034 29.325062 270)
			(size 0.519938 1.4986)
			(layers "F.Cu" "F.Mask" "F.Paste")
			(net "GND")
		)
		(pad "249" smd rect
			(at 2.050034 30.174946 270)
			(size 0.519938 1.4986)
			(layers "F.Cu" "F.Mask" "F.Paste")
			(net "M_H_CPU0_SB_DQS_DN<5>")
		)
		(pad "250" smd rect
			(at 2.050034 31.025084 270)
			(size 0.519938 1.4986)
			(layers "F.Cu" "F.Mask" "F.Paste")
			(net "M_H_CPU0_SB_DQS_DP<5>")
		)
		(pad "251" smd rect
			(at 2.050034 31.874968 270)
			(size 0.519938 1.4986)
			(layers "F.Cu" "F.Mask" "F.Paste")
			(net "GND")
		)
		(pad "252" smd rect
			(at 2.050034 32.725106 270)
			(size 0.519938 1.4986)
			(layers "F.Cu" "F.Mask" "F.Paste")
			(net "M_H_CPU0_SB_DQ<6>")
		)
		(pad "253" smd rect
			(at 2.050034 33.57499 270)
			(size 0.519938 1.4986)
			(layers "F.Cu" "F.Mask" "F.Paste")
			(net "GND")
		)
		(pad "254" smd rect
			(at 2.050034 34.425128 270)
			(size 0.519938 1.4986)
			(layers "F.Cu" "F.Mask" "F.Paste")
			(net "M_H_CPU0_SB_DQ<7>")
		)
		(pad "255" smd rect
			(at 2.050034 35.275012 270)
			(size 0.519938 1.4986)
			(layers "F.Cu" "F.Mask" "F.Paste")
			(net "GND")
		)
		(pad "256" smd rect
			(at 2.050034 36.124896 270)
			(size 0.519938 1.4986)
			(layers "F.Cu" "F.Mask" "F.Paste")
			(net "M_H_CPU0_SB_DQ<10>")
		)
		(pad "257" smd rect
			(at 2.050034 36.975034 270)
			(size 0.519938 1.4986)
			(layers "F.Cu" "F.Mask" "F.Paste")
			(net "GND")
		)
		(pad "258" smd rect
			(at 2.050034 37.824918 270)
			(size 0.519938 1.4986)
			(layers "F.Cu" "F.Mask" "F.Paste")
			(net "M_H_CPU0_SB_DQ<11>")
		)
		(pad "259" smd rect
			(at 2.050034 38.675056 270)
			(size 0.519938 1.4986)
			(layers "F.Cu" "F.Mask" "F.Paste")
			(net "GND")
		)
		(pad "260" smd rect
			(at 2.050034 39.52494 270)
			(size 0.519938 1.4986)
			(layers "F.Cu" "F.Mask" "F.Paste")
			(net "M_H_CPU0_SB_DQS_DN<6>")
		)
		(pad "261" smd rect
			(at 2.050034 40.375078 270)
			(size 0.519938 1.4986)
			(layers "F.Cu" "F.Mask" "F.Paste")
			(net "M_H_CPU0_SB_DQS_DP<6>")
		)
		(pad "262" smd rect
			(at 2.050034 41.224962 270)
			(size 0.519938 1.4986)
			(layers "F.Cu" "F.Mask" "F.Paste")
			(net "GND")
		)
		(pad "263" smd rect
			(at 2.050034 42.0751 270)
			(size 0.519938 1.4986)
			(layers "F.Cu" "F.Mask" "F.Paste")
			(net "M_H_CPU0_SB_DQ<14>")
		)
		(pad "264" smd rect
			(at 2.050034 42.924984 270)
			(size 0.519938 1.4986)
			(layers "F.Cu" "F.Mask" "F.Paste")
			(net "GND")
		)
		(pad "265" smd rect
			(at 2.050034 43.775122 270)
			(size 0.519938 1.4986)
			(layers "F.Cu" "F.Mask" "F.Paste")
			(net "M_H_CPU0_SB_DQ<15>")
		)
		(pad "266" smd rect
			(at 2.050034 44.625006 270)
			(size 0.519938 1.4986)
			(layers "F.Cu" "F.Mask" "F.Paste")
			(net "GND")
		)
		(pad "267" smd rect
			(at 2.050034 45.47489 270)
			(size 0.519938 1.4986)
			(layers "F.Cu" "F.Mask" "F.Paste")
			(net "M_H_CPU0_SB_DQ<18>")
		)
		(pad "268" smd rect
			(at 2.050034 46.325028 270)
			(size 0.519938 1.4986)
			(layers "F.Cu" "F.Mask" "F.Paste")
			(net "GND")
		)
		(pad "269" smd rect
			(at 2.050034 47.174912 270)
			(size 0.519938 1.4986)
			(layers "F.Cu" "F.Mask" "F.Paste")
			(net "M_H_CPU0_SB_DQ<19>")
		)
		(pad "270" smd rect
			(at 2.050034 48.02505 270)
			(size 0.519938 1.4986)
			(layers "F.Cu" "F.Mask" "F.Paste")
			(net "GND")
		)
		(pad "271" smd rect
			(at 2.050034 48.874934 270)
			(size 0.519938 1.4986)
			(layers "F.Cu" "F.Mask" "F.Paste")
			(net "M_H_CPU0_SB_DQS_DN<7>")
		)
		(pad "272" smd rect
			(at 2.050034 49.725072 270)
			(size 0.519938 1.4986)
			(layers "F.Cu" "F.Mask" "F.Paste")
			(net "M_H_CPU0_SB_DQS_DP<7>")
		)
		(pad "273" smd rect
			(at 2.050034 50.574956 270)
			(size 0.519938 1.4986)
			(layers "F.Cu" "F.Mask" "F.Paste")
			(net "GND")
		)
		(pad "274" smd rect
			(at 2.050034 51.425094 270)
			(size 0.519938 1.4986)
			(layers "F.Cu" "F.Mask" "F.Paste")
			(net "M_H_CPU0_SB_DQ<22>")
		)
	)
)
